# T6G (Grand Teton) — schematic netlist excerpt (pin names and nets, part order shuffled) for the footprints in the layout excerpt that follows; sources: Cadence DE-HDL packaged netlist, KiCad conversion of 04192023_DAF0TMB3IC0_F0TG_MB_C_brd_V02_OCP.brd

X26  TP_TDR_4P_FTS  TP_TDR_4P_DIP EMPTY  pkg TH  page 260
  S1  = TDR_DIFF_80_IN6_DP
  P1  = T1_GND
  P2  = T1_GND
  S2  = TDR_DIFF_80_IN6_DN

R1384  Q_RES  2K 1% EMPTY  pkg 0402LF  page 151 : A = SMB_CPU0_CPU1_SEC_SCL ; B = P3V3_AUX

(kicad_pcb
	(version 20260206)
	(generator "pcbnew")
	(generator_version "10.0")
	(general
		(thickness 1.6)
		(legacy_teardrops no)
	)
	(paper "A4")
	(title_block
		(title "04192023_DAF0TMB3IC0_F0TG_MB_C_brd_V02_OCP.brd")
		(comment 1 "Grand Teton / footprints 6554-6555 of 8354")
	)
	(layers
		(0 "F.Cu" signal "TOP")
		(4 "In1.Cu" signal "GND")
		(6 "In2.Cu" signal "IN1")
		(8 "In3.Cu" signal "GND1")
		(10 "In4.Cu" signal "IN2")
		(12 "In5.Cu" signal "GND2")
		(14 "In6.Cu" signal "IN3")
		(16 "In7.Cu" signal "GND3")
		(18 "In8.Cu" signal "VCC")
		(20 "In9.Cu" signal "VCC1")
		(22 "In10.Cu" signal "GND4")
		(24 "In11.Cu" signal "IN4")
		(26 "In12.Cu" signal "GND5")
		(28 "In13.Cu" signal "IN5")
		(30 "In14.Cu" signal "GND6")
		(32 "In15.Cu" signal "IN6")
		(34 "In16.Cu" signal "GND7")
		(2 "B.Cu" signal "BOTTOM")
		(9 "F.Adhes" user "F.Adhesive")
		(11 "B.Adhes" user "B.Adhesive")
		(13 "F.Paste" user "Package Geometry/Pastemask Top")
		(15 "B.Paste" user "Package Geometry/Pastemask Bottom")
		(5 "F.SilkS" user "Ref Des/Silkscreen Top")
		(7 "B.SilkS" user "Ref Des/Silkscreen Bottom")
		(1 "F.Mask" user "Board Geometry/Soldermask Top")
		(3 "B.Mask" user "Board Geometry/Soldermask Bottom")
		(17 "Dwgs.User" user "User.Drawings")
		(19 "Cmts.User" user "User.Comments")
		(21 "Eco1.User" user "User.Eco1")
		(23 "Eco2.User" user "User.Eco2")
		(25 "Edge.Cuts" user "Board Geometry/Outline")
		(27 "Margin" user)
		(31 "F.CrtYd" user "Package Geometry/Place Bound Top")
		(29 "B.CrtYd" user "Package Geometry/Place Bound Bottom")
		(35 "F.Fab" user "Ref Des/Assembly Top")
		(33 "B.Fab" user "Ref Des/Assembly Bottom")
	)
	(footprint ""
		(layer "B.Cu")
		(at 501.233948 -298.343066 -90)
		(property "Reference" "X26"
			(at 3.089656 3.232658 270)
			(unlocked yes)
			(layer "B.SilkS")
			(effects
				(font
					(size 0.7874 0.5842)
					(thickness 0.1524)
				)
				(justify left mirror)
			)
		)
		(property "Value" ""
			(at 0 0 90)
			(layer "B.Fab")
			(effects
				(font
					(size 1.27 1.27)
				)
				(justify mirror)
			)
		)
		(property "User Part Number" "N_A"
			(at -1.30175 1.27 180)
			(unlocked yes)
			(layer "Cmts.User")
			(hide yes)
			(effects
				(font
					(size 0.635 0.4064)
					(thickness 0.1524)
				)
				(justify mirror)
			)
		)
		(property "Device Type" "TP_TDR_4P_FTS_TH-TP_TDR_4P_DIP,EMPTY,TP15"
			(at -1.30175 1.27 180)
			(unlocked yes)
			(layer "B.Fab")
			(hide yes)
			(effects
				(font
					(size 0.635 0.4064)
					(thickness 0.1524)
				)
				(justify mirror)
			)
		)
		(duplicate_pad_numbers_are_jumpers no)
		(fp_line
			(start -2.54 3.81)
			(end -2.54 3.6703)
			(stroke
				(width 0.1524)
				(type default)
			)
			(layer "B.SilkS")
		)
		(fp_line
			(start 0 3.81)
			(end -2.54 3.81)
			(stroke
				(width 0.1524)
				(type default)
			)
			(layer "B.SilkS")
		)
		(fp_line
			(start 0 3.175)
			(end 0 3.81)
			(stroke
				(width 0.1524)
				(type default)
			)
			(layer "B.SilkS")
		)
		(fp_line
			(start -2.54 1.4097)
			(end -2.54 1.1303)
			(stroke
				(width 0.1524)
				(type default)
			)
			(layer "B.SilkS")
		)
		(fp_line
			(start 0 0.635)
			(end 0 1.905)
			(stroke
				(width 0.1524)
				(type default)
			)
			(layer "B.SilkS")
		)
		(fp_line
			(start -2.54 -1.1303)
			(end -2.54 -1.27)
			(stroke
				(width 0.1524)
				(type default)
			)
			(layer "B.SilkS")
		)
		(fp_line
			(start -2.54 -1.27)
			(end 0 -1.27)
			(stroke
				(width 0.1524)
				(type default)
			)
			(layer "B.SilkS")
		)
		(fp_line
			(start 0 -1.27)
			(end 0 -0.635)
			(stroke
				(width 0.1524)
				(type default)
			)
			(layer "B.SilkS")
		)
		(fp_poly
			(pts
				(xy 2.285746 -0.762) (xy 2.285746 0.762) (xy 0.761746 0)
			)
			(stroke
				(width 0)
				(type default)
			)
			(fill yes)
			(layer "B.SilkS")
		)
		(fp_line
			(start -2.54 3.81)
			(end -2.54 -1.27)
			(stroke
				(width 0.1)
				(type default)
			)
			(layer "B.Fab")
		)
		(fp_line
			(start 0 3.81)
			(end -2.54 3.81)
			(stroke
				(width 0.1)
				(type default)
			)
			(layer "B.Fab")
		)
		(fp_line
			(start -2.54 -1.27)
			(end 0 -1.27)
			(stroke
				(width 0.1)
				(type default)
			)
			(layer "B.Fab")
		)
		(fp_line
			(start 0 -1.27)
			(end 0 3.81)
			(stroke
				(width 0.1)
				(type default)
			)
			(layer "B.Fab")
		)
		(fp_poly
			(pts
				(xy 0.761746 0) (xy 2.285746 -0.762) (xy 2.285746 0.762)
			)
			(stroke
				(width 0)
				(type default)
			)
			(fill yes)
			(layer "B.Fab")
		)
		(pad "1" thru_hole circle
			(at 0 0 90)
			(size 1.0033 1.0033)
			(drill 0.249936)
			(layers "*.Cu" "*.Mask")
			(remove_unused_layers no)
			(net "TDR_DIFF_80_IN6_DP")
			(clearance 0.10795)
			(padstack
				(mode front_inner_back)
				(layer "Inner"
					(shape circle)
					(size 0.8001 0.8001)
					(clearance 0.1524)
				)
				(layer "B.Cu"
					(shape circle)
					(size 1.0033 1.0033)
					(thermal_gap 0.10795)
					(clearance 0.10795)
				)
			)
		)
		(pad "2" thru_hole circle
			(at -2.54 0 90)
			(size 1.9939 1.9939)
			(drill 0.249936)
			(layers "*.Cu" "*.Mask")
			(remove_unused_layers no)
			(net "T1_GND")
			(clearance 0.10795)
			(padstack
				(mode front_inner_back)
				(layer "Inner"
					(shape circle)
					(size 0.8001 0.8001)
					(clearance 0.1524)
				)
				(layer "B.Cu"
					(shape circle)
					(size 1.9939 1.9939)
					(thermal_gap 0.10795)
					(clearance 0.10795)
				)
			)
		)
		(pad "3" thru_hole circle
			(at -2.54 2.54 90)
			(size 1.9939 1.9939)
			(drill 0.249936)
			(layers "*.Cu" "*.Mask")
			(remove_unused_layers no)
			(net "T1_GND")
			(clearance 0.10795)
			(padstack
				(mode front_inner_back)
				(layer "Inner"
					(shape circle)
					(size 0.8001 0.8001)
					(clearance 0.1524)
				)
				(layer "B.Cu"
					(shape circle)
					(size 1.9939 1.9939)
					(thermal_gap 0.10795)
					(clearance 0.10795)
				)
			)
		)
		(pad "4" thru_hole circle
			(at 0 2.54 90)
			(size 1.0033 1.0033)
			(drill 0.249936)
			(layers "*.Cu" "*.Mask")
			(remove_unused_layers no)
			(net "TDR_DIFF_80_IN6_DN")
			(clearance 0.10795)
			(padstack
				(mode front_inner_back)
				(layer "Inner"
					(shape circle)
					(size 0.8001 0.8001)
					(clearance 0.1524)
				)
				(layer "B.Cu"
					(shape circle)
					(size 1.0033 1.0033)
					(thermal_gap 0.10795)
					(clearance 0.10795)
				)
			)
		)
	)
	(footprint ""
		(layer "B.Cu")
		(at 178.430174 -13.756132 90)
		(property "Reference" "R1384"
			(at 0 0 90)
			(layer "B.SilkS")
			(hide yes)
			(effects
				(font
					(size 1.27 1.27)
				)
				(justify mirror)
			)
		)
		(property "Value" ""
			(at 0 0 90)
			(layer "B.Fab")
			(effects
				(font
					(size 1.27 1.27)
				)
				(justify mirror)
			)
		)
		(duplicate_pad_numbers_are_jumpers no)
		(fp_line
			(start 0.7874 -0.4064)
			(end -0.7874 -0.4064)
			(stroke
				(width 0.1524)
				(type default)
			)
			(layer "B.SilkS")
		)
		(fp_line
			(start -0.7874 -0.4064)
			(end -0.7874 0.4064)
			(stroke
				(width 0.1524)
				(type default)
			)
			(layer "B.SilkS")
		)
		(fp_line
			(start 0.7874 0.4064)
			(end 0.7874 -0.4064)
			(stroke
				(width 0.1524)
				(type default)
			)
			(layer "B.SilkS")
		)
		(fp_line
			(start -0.7874 0.4064)
			(end 0.7874 0.4064)
			(stroke
				(width 0.1524)
				(type default)
			)
			(layer "B.SilkS")
		)
		(fp_line
			(start 0.67945 -0.305054)
			(end 0.12065 -0.305054)
			(stroke
				(width 0.1)
				(type default)
			)
			(layer "B.Fab")
		)
		(fp_line
			(start 0.12065 -0.305054)
			(end 0.12065 -0.2794)
			(stroke
				(width 0.1)
				(type default)
			)
			(layer "B.Fab")
		)
		(fp_line
			(start -0.12065 -0.3048)
			(end -0.67945 -0.3048)
			(stroke
				(width 0.1)
				(type default)
			)
			(layer "B.Fab")
		)
		(fp_line
			(start -0.67945 -0.3048)
			(end -0.67945 0.3048)
			(stroke
				(width 0.1)
				(type default)
			)
			(layer "B.Fab")
		)
		(fp_line
			(start 0.12065 -0.2794)
			(end -0.12065 -0.2794)
			(stroke
				(width 0.1)
				(type default)
			)
			(layer "B.Fab")
		)
		(fp_line
			(start -0.12065 -0.2794)
			(end -0.12065 -0.3048)
			(stroke
				(width 0.1)
				(type default)
			)
			(layer "B.Fab")
		)
		(fp_line
			(start 0.12065 0.2794)
			(end 0.12065 0.3048)
			(stroke
				(width 0.1)
				(type default)
			)
			(layer "B.Fab")
		)
		(fp_line
			(start -0.120396 0.2794)
			(end 0.12065 0.2794)
			(stroke
				(width 0.1)
				(type default)
			)
			(layer "B.Fab")
		)
		(fp_line
			(start 0.67945 0.3048)
			(end 0.67945 -0.305054)
			(stroke
				(width 0.1)
				(type default)
			)
			(layer "B.Fab")
		)
		(fp_line
			(start 0.12065 0.3048)
			(end 0.67945 0.3048)
			(stroke
				(width 0.1)
				(type default)
			)
			(layer "B.Fab")
		)
		(fp_line
			(start -0.120396 0.3048)
			(end -0.120396 0.2794)
			(stroke
				(width 0.1)
				(type default)
			)
			(layer "B.Fab")
		)
		(fp_line
			(start -0.67945 0.3048)
			(end -0.120396 0.3048)
			(stroke
				(width 0.1)
				(type default)
			)
			(layer "B.Fab")
		)
		(pad "1" smd circle
			(at 0.40005 0 270)
			(size 0 0)
			(layers "B.Cu" "B.Mask" "B.Paste")
			(net "SMB_CPU0_CPU1_SEC_SCL")
		)
		(pad "2" smd circle
			(at -0.40005 0 270)
			(size 0 0)
			(layers "B.Cu" "B.Mask" "B.Paste")
			(net "P3V3_AUX")
		)
	)
)
